# T6G (Grand Teton) — schematic parts with pin connectivity, parts 8082–8082 of 8303; source: Cadence DE-HDL packaged netlist (pstxprt.dat, pstxnet.dat, pstchip.dat)

U26  GENOA_SP5  SOCKET6096_13568-001 IO  pkg SOCKET6096_93-4X120-45XA  page 37  (pins 1345-1680 of 6096)
  AV67  MFA0_CS_L0  OUT  = M_F_CPU1_SA_CS_N<0>
  AV68  VSS_AV68  POWER  = GND
  AV69  MEA1_CS_L1  OUT  = NC
  AV70  MEA0_CS_L0  OUT  = M_E_CPU1_SA_CS_N<0>
  AV71  VDDIO_AV71  POWER  = PVDDIO_P1
  AV72  MAA1_CS_L1  OUT  = NC
  AV73  VSS_AV73  POWER  = GND
  AV74  MAA0_CS_L0  OUT  = M_A_CPU1_SA_CS_N<0>
  AW1  VSS_AW1  POWER  = GND
  AW2  MGA_CA0  OUT  = M_G_CPU1_SA_CA<0>
  AW3  MGA1_CS_L1  OUT  = NC
  AW4  VSS_AW4  POWER  = GND
  AW5  MKA_CA0  OUT  = M_K_CPU1_SA_CA<0>
  AW6  VSS_AW6  POWER  = GND
  AW7  MKA1_CS_L1  OUT  = NC
  AW8  VSS_AW8  POWER  = GND
  AW9  MLA_CA0  OUT  = M_L_CPU1_SA_CA<0>
  AW10  MLA1_CS_L1  OUT  = NC
  AW11  VSS_AW11  POWER  = GND
  AW12  MHA_CA0  OUT  = M_H_CPU1_SA_CA<0>
  AW13  VSS_AW13  POWER  = GND
  AW14  MHA1_CS_L1  OUT  = NC
  AW15  VSS_AW15  POWER  = GND
  AW16  MJA_CA0  OUT  = M_J_CPU1_SA_CA<0>
  AW17  MJA1_CS_L1  OUT  = NC
  AW18  VSS_AW18  POWER  = GND
  AW19  MIA_CA0  OUT  = M_I_CPU1_SA_CA<0>
  AW20  VSS_AW20  POWER  = GND
  AW21  MIA1_CS_L1  OUT  = NC
  AW22  VSS_AW22  POWER  = GND
  AW23  VDDCR_SOC_AW23  POWER  = PVDDCR_SOC_P1
  AW24  VSS_AW24  POWER  = GND
  AW25  VDDCR_SOC_AW25  POWER  = PVDDCR_SOC_P1
  AW26  VSS_AW26  POWER  = GND
  AW27  VDDCR_SOC_AW27  POWER  = PVDDCR_SOC_P1
  AW28  VSS_AW28  POWER  = GND
  AW48  VDDCR_SOC_AW48  POWER  = PVDDCR_SOC_P1
  AW49  VSS_AW49  POWER  = GND
  AW50  VDD_18_S5_AW50  POWER  = PVDD18_S5_P1
  AW51  VSS_AW51  POWER  = GND
  AW52  VDD_18_S5_AW52  POWER  = PVDD18_S5_P1
  AW53  VSS_AW53  POWER  = GND
  AW54  VDD_18_S5_AW54  POWER  = PVDD18_S5_P1
  AW55  MCA0_CS_L1  OUT  = M_C_CPU1_SA_CS_N<1>
  AW56  VSS_AW56  POWER  = GND
  AW57  MCA_CA0  OUT  = M_C_CPU1_SA_CA<0>
  AW58  VSS_AW58  POWER  = GND
  AW59  MDA0_CS_L1  OUT  = M_D_CPU1_SA_CS_N<1>
  AW60  MDA_CA0  OUT  = M_D_CPU1_SA_CA<0>
  AW61  VSS_AW61  POWER  = GND
  AW62  MBA0_CS_L1  OUT  = M_B_CPU1_SA_CS_N<1>
  AW63  VSS_AW63  POWER  = GND
  AW64  MBA_CA0  OUT  = M_B_CPU1_SA_CA<0>
  AW65  VSS_AW65  POWER  = GND
  AW66  MFA0_CS_L1  OUT  = M_F_CPU1_SA_CS_N<1>
  AW67  MFA_CA0  OUT  = M_F_CPU1_SA_CA<0>
  AW68  VSS_AW68  POWER  = GND
  AW69  MEA0_CS_L1  OUT  = M_E_CPU1_SA_CS_N<1>
  AW70  VSS_AW70  POWER  = GND
  AW71  MEA_CA0  OUT  = M_E_CPU1_SA_CA<0>
  AW72  VSS_AW72  POWER  = GND
  AW73  MAA0_CS_L1  OUT  = M_A_CPU1_SA_CS_N<1>
  AW74  MAA_CA0  OUT  = M_A_CPU1_SA_CA<0>
  AW75  VSS_AW75  POWER  = GND
  AY2  MGA_CA1  OUT  = M_G_CPU1_SA_CA<1>
  AY3  VSS_AY3  POWER  = GND
  AY4  MGA_CA2  OUT  = M_G_CPU1_SA_CA<2>
  AY5  VSS_AY5  POWER  = GND
  AY6  MKA_CA1  OUT  = M_K_CPU1_SA_CA<1>
  AY7  MKA_CA2  OUT  = M_K_CPU1_SA_CA<2>
  AY8  VSS_AY8  POWER  = GND
  AY9  MLA_CA1  OUT  = M_L_CPU1_SA_CA<1>
  AY10  VSS_AY10  POWER  = GND
  AY11  MLA_CA2  OUT  = M_L_CPU1_SA_CA<2>
  AY12  VSS_AY12  POWER  = GND
  AY13  MHA_CA1  OUT  = M_H_CPU1_SA_CA<1>
  AY14  MHA_CA2  OUT  = M_H_CPU1_SA_CA<2>
  AY15  VSS_AY15  POWER  = GND
  AY16  MJA_CA1  OUT  = M_J_CPU1_SA_CA<1>
  AY17  VSS_AY17  POWER  = GND
  AY18  MJA_CA2  OUT  = M_J_CPU1_SA_CA<2>
  AY19  VSS_AY19  POWER  = GND
  AY20  MIA_CA1  OUT  = M_I_CPU1_SA_CA<1>
  AY21  MIA_CA2  OUT  = M_I_CPU1_SA_CA<2>
  AY22  VDDCR_SOC_AY22  POWER  = PVDDCR_SOC_P1
  AY23  VSS_AY23  POWER  = GND
  AY24  VDDCR_SOC_AY24  POWER  = PVDDCR_SOC_P1
  AY25  VSS_AY25  POWER  = GND
  AY26  VDDCR_SOC_AY26  POWER  = PVDDCR_SOC_P1
  AY27  VSS_AY27  POWER  = GND
  AY28  VDDCR_SOC_AY28  POWER  = PVDDCR_SOC_P1
  AY48  VSS_AY48  POWER  = GND
  AY49  VDDCR_SOC_AY49  POWER  = PVDDCR_SOC_P1
  AY50  VSS_AY50  POWER  = GND
  AY51  VDD_18_S5_AY51  POWER  = PVDD18_S5_P1
  AY52  VSS_AY52  POWER  = GND
  AY53  VDD_18_S5_AY53  POWER  = PVDD18_S5_P1
  AY54  VSS_AY54  POWER  = GND
  AY55  MCA_CA2  OUT  = M_C_CPU1_SA_CA<2>
  AY56  MCA_CA1  OUT  = M_C_CPU1_SA_CA<1>
  AY57  VSS_AY57  POWER  = GND
  AY58  MDA_CA2  OUT  = M_D_CPU1_SA_CA<2>
  AY59  VSS_AY59  POWER  = GND
  AY60  MDA_CA1  OUT  = M_D_CPU1_SA_CA<1>
  AY61  VSS_AY61  POWER  = GND
  AY62  MBA_CA2  OUT  = M_B_CPU1_SA_CA<2>
  AY63  MBA_CA1  OUT  = M_B_CPU1_SA_CA<1>
  AY64  VSS_AY64  POWER  = GND
  AY65  MFA_CA2  OUT  = M_F_CPU1_SA_CA<2>
  AY66  VSS_AY66  POWER  = GND
  AY67  MFA_CA1  OUT  = M_F_CPU1_SA_CA<1>
  AY68  VSS_AY68  POWER  = GND
  AY69  MEA_CA2  OUT  = M_E_CPU1_SA_CA<2>
  AY70  MEA_CA1  OUT  = M_E_CPU1_SA_CA<1>
  AY71  VSS_AY71  POWER  = GND
  AY72  MAA_CA2  OUT  = M_A_CPU1_SA_CA<2>
  AY73  VSS_AY73  POWER  = GND
  AY74  MAA_CA1  OUT  = M_A_CPU1_SA_CA<1>
  B3  VDDCR_SOC_SENSE  POWER  = VSENSE_PVDDCR_SOC_P1_DP
  B4  \i3c3_sda||i2c3_sda||spd3_sda||agpio152\  BI  = NC
  B5  VDDCR_SOC_B5  POWER  = PVDDCR_SOC_P1
  B6  GPP_CLK02P  OUT  = CLK_100M_CPU1_CLK02_R_DP
  B7  VSS_B7  POWER  = GND
  B8  VSS_B8  POWER  = GND
  B9  GPP_CLK05P  OUT  = CLK_100M_CPU1_CLK05_R_DP
  B10  VSS_B10  POWER  = GND
  B11  VSS_B11  POWER  = GND
  B12  GPP_CLK04P  OUT  = CLK_100M_CPU1_CLK04_R_DP
  B13  VSS_B13  POWER  = GND
  B14  \sec_scl||agpio262\  BI  = SMB_CPU1_SEC_SCL
  B15  \sgpio_load||agpio261\  BI  = NC
  B16  \agpio259||sgpio3_clk\  BI  = NC
  B17  TCK  IN  = JTAG_CPU1_TCK
  B18  VSS_B18  POWER  = GND
  B19  VDDCR_CPU0_B19  POWER  = PVDDCR_CPU0_P1
  B20  VDDCR_CPU0_B20  POWER  = PVDDCR_CPU0_P1
  B21  SVT0  IN  = SVID_PVDDCR_CPU0_P1_SVTO
  B22  VDDCR_CPU0_B22  POWER  = PVDDCR_CPU0_P1
  B23  VDDCR_CPU0_B23  POWER  = PVDDCR_CPU0_P1
  B24  VSS_B24  POWER  = GND
  B25  VDDCR_CPU0_B25  POWER  = PVDDCR_CPU0_P1
  B26  VDDCR_CPU0_B26  POWER  = PVDDCR_CPU0_P1
  B27  VSS_B27  POWER  = GND
  B28  VDDCR_CPU0_B28  POWER  = PVDDCR_CPU0_P1
  B29  VDDCR_CPU0_B29  POWER  = PVDDCR_CPU0_P1
  B30  VSS_B30  POWER  = GND
  B31  VDDCR_CPU0_B31  POWER  = PVDDCR_CPU0_P1
  B32  VDDCR_CPU0_B32  POWER  = PVDDCR_CPU0_P1
  B33  VSS_B33  POWER  = GND
  B34  VDDCR_CPU0_B34  POWER  = PVDDCR_CPU0_P1
  B35  VDDCR_CPU0_B35  POWER  = PVDDCR_CPU0_P1
  B36  TEST6_X3D6  OUT  = NC
  B37  VSS_B37  POWER  = GND
  B39  VSS_B39  POWER  = GND
  B40  RSVD_B40  TRI  = NC
  B41  VDDCR_CPU0_B41  POWER  = PVDDCR_CPU0_P1
  B42  VDDCR_CPU0_B42  POWER  = PVDDCR_CPU0_P1
  B43  VSS_B43  POWER  = GND
  B44  VDDCR_CPU0_B44  POWER  = PVDDCR_CPU0_P1
  B45  VDDCR_CPU0_B45  POWER  = PVDDCR_CPU0_P1
  B46  VSS_B46  POWER  = GND
  B47  VDDCR_CPU0_B47  POWER  = PVDDCR_CPU0_P1
  B48  VDDCR_CPU0_B48  POWER  = PVDDCR_CPU0_P1
  B49  VSS_B49  POWER  = GND
  B50  VDDCR_CPU0_B50  POWER  = PVDDCR_CPU0_P1
  B51  VDDCR_CPU0_B51  POWER  = PVDDCR_CPU0_P1
  B52  VSS_B52  POWER  = GND
  B53  VDDCR_CPU0_B53  POWER  = PVDDCR_CPU0_P1
  B54  VDDCR_CPU0_B54  POWER  = PVDDCR_CPU0_P1
  B55  VSS_B55  POWER  = GND
  B56  VDDCR_CPU0_B56  POWER  = PVDDCR_CPU0_P1
  B57  VDDCR_CPU0_B57  POWER  = PVDDCR_CPU0_P1
  B58  TEST47_IOD0  TRI  = TP_CPU1_TEST47_IOD0
  B59  VSS_B59  POWER  = GND
  B60  TEST47_CCD0  TRI  = TP_CPU1_TEST47_CCD0
  B61  TEST50_IOD  TRI  = TP_CPU1_TEST50_IOD
  B62  VSS_B62  POWER  = GND
  B63  FORCE_SELFREFRESH  IN  = CPU1_FORCE_SELFREFRESH
  B64  NV_SAVE_L  OUT  = CPU1_NV_SAVE_N
  B65  VSS_B65  POWER  = GND
  B66  CPU_PRESENT_L  OUT  = PRSNT_CPU1_N
  B67  RESET_L  BI  = RST_CPU1_RESETL_N
  B68  VSS_B68  POWER  = GND
  B69  CORETYPE1  OUT  = CPU1_CORETYPE1
  B70  VSS_B70  POWER  = GND
  B71  \i3c0_sda||i2c0_sda||spd0_sda||smbus0_sda||agpio146\  BI  = I3C_0_SPD_DDRAF_CPU1_R_SDA
  B72  \i3c2_sda||i2c2_sda||spd2_sda||agpio150\  BI  = NC
  B73  VSS_SENSE_D  POWER  = VSENSE_PVDD18_S5_P1_DN
  BA1  VSS_BA1  POWER  = GND
  BA2  MGA_CA4  OUT  = M_G_CPU1_SA_CA<4>
  BA3  MGA_CA3  OUT  = M_G_CPU1_SA_CA<3>
  BA4  VDDCR_SOC_BA4  POWER  = PVDDCR_SOC_P1
  BA5  MKA_CA4  OUT  = M_K_CPU1_SA_CA<4>
  BA6  VSS_BA6  POWER  = GND
  BA7  MKA_CA3  OUT  = M_K_CPU1_SA_CA<3>
  BA8  VSS_BA8  POWER  = GND
  BA9  MLA_CA4  OUT  = M_L_CPU1_SA_CA<4>
  BA10  MLA_CA3  OUT  = M_L_CPU1_SA_CA<3>
  BA11  VDDCR_SOC_BA11  POWER  = PVDDCR_SOC_P1
  BA12  MHA_CA4  OUT  = M_H_CPU1_SA_CA<4>
  BA13  VSS_BA13  POWER  = GND
  BA14  MHA_CA3  OUT  = M_H_CPU1_SA_CA<3>
  BA15  VSS_BA15  POWER  = GND
  BA16  MJA_CA4  OUT  = M_J_CPU1_SA_CA<4>
  BA17  MJA_CA3  OUT  = M_J_CPU1_SA_CA<3>
  BA18  VDDCR_SOC_BA18  POWER  = PVDDCR_SOC_P1
  BA19  MIA_CA4  OUT  = M_I_CPU1_SA_CA<4>
  BA20  VSS_BA20  POWER  = GND
  BA21  MIA_CA3  OUT  = M_I_CPU1_SA_CA<3>
  BA22  VSS_BA22  POWER  = GND
  BA23  VDDCR_SOC_BA23  POWER  = PVDDCR_SOC_P1
  BA24  VSS_BA24  POWER  = GND
  BA25  VDDCR_SOC_BA25  POWER  = PVDDCR_SOC_P1
  BA26  VSS_BA26  POWER  = GND
  BA27  VDDCR_SOC_BA27  POWER  = PVDDCR_SOC_P1
  BA28  VSS_BA28  POWER  = GND
  BA48  VDDCR_SOC_BA48  POWER  = PVDDCR_SOC_P1
  BA49  VSS_BA49  POWER  = GND
  BA50  VDD_18_S5_BA50  POWER  = PVDD18_S5_P1
  BA51  VSS_BA51  POWER  = GND
  BA52  VDD_18_S5_BA52  POWER  = PVDD18_S5_P1
  BA53  VSS_BA53  POWER  = GND
  BA54  VDD_18_S5_BA54  POWER  = PVDD18_S5_P1
  BA55  MCA_CA3  OUT  = M_C_CPU1_SA_CA<3>
  BA56  VSS_BA56  POWER  = GND
  BA57  MCA_CA4  OUT  = M_C_CPU1_SA_CA<4>
  BA58  VDDIO_BA58  POWER  = PVDDIO_P1
  BA59  MDA_CA3  OUT  = M_D_CPU1_SA_CA<3>
  BA60  MDA_CA4  OUT  = M_D_CPU1_SA_CA<4>
  BA61  VSS_BA61  POWER  = GND
  BA62  MBA_CA3  OUT  = M_B_CPU1_SA_CA<3>
  BA63  VSS_BA63  POWER  = GND
  BA64  MBA_CA4  OUT  = M_B_CPU1_SA_CA<4>
  BA65  VDDIO_BA65  POWER  = PVDDIO_P1
  BA66  MFA_CA3  OUT  = M_F_CPU1_SA_CA<3>
  BA67  MFA_CA4  OUT  = M_F_CPU1_SA_CA<4>
  BA68  VSS_BA68  POWER  = GND
  BA69  MEA_CA3  OUT  = M_E_CPU1_SA_CA<3>
  BA70  VSS_BA70  POWER  = GND
  BA71  MEA_CA4  OUT  = M_E_CPU1_SA_CA<4>
  BA72  VDDIO_BA72  POWER  = PVDDIO_P1
  BA73  MAA_CA3  OUT  = M_A_CPU1_SA_CA<3>
  BA74  MAA_CA4  OUT  = M_A_CPU1_SA_CA<4>
  BA75  VSS_BA75  POWER  = GND
  BB2  MGA_CA5  OUT  = M_G_CPU1_SA_CA<5>
  BB3  VSS_BB3  POWER  = GND
  BB4  MGA_CA6  OUT  = M_G_CPU1_SA_CA<6>
  BB5  VSS_BB5  POWER  = GND
  BB6  MKA_CA5  OUT  = M_K_CPU1_SA_CA<5>
  BB7  MKA_CA6  OUT  = M_K_CPU1_SA_CA<6>
  BB8  VSS_BB8  POWER  = GND
  BB9  MLA_CA5  OUT  = M_L_CPU1_SA_CA<5>
  BB10  VSS_BB10  POWER  = GND
  BB11  MLA_CA6  OUT  = M_L_CPU1_SA_CA<6>
  BB12  VSS_BB12  POWER  = GND
  BB13  MHA_CA5  OUT  = M_H_CPU1_SA_CA<5>
  BB14  MHA_CA6  OUT  = M_H_CPU1_SA_CA<6>
  BB15  VSS_BB15  POWER  = GND
  BB16  MJA_CA5  OUT  = M_J_CPU1_SA_CA<5>
  BB17  VSS_BB17  POWER  = GND
  BB18  MJA_CA6  OUT  = M_J_CPU1_SA_CA<6>
  BB19  VSS_BB19  POWER  = GND
  BB20  MIA_CA5  OUT  = M_I_CPU1_SA_CA<5>
  BB21  MIA_CA6  OUT  = M_I_CPU1_SA_CA<6>
  BB22  VDDCR_SOC_BB22  POWER  = PVDDCR_SOC_P1
  BB23  VSS_BB23  POWER  = GND
  BB24  VDDCR_SOC_BB24  POWER  = PVDDCR_SOC_P1
  BB25  VSS_BB25  POWER  = GND
  BB26  VDDCR_SOC_BB26  POWER  = PVDDCR_SOC_P1
  BB27  VSS_BB27  POWER  = GND
  BB28  VDDCR_SOC_BB28  POWER  = PVDDCR_SOC_P1
  BB48  VSS_BB48  POWER  = GND
  BB49  VDDCR_SOC_BB49  POWER  = PVDDCR_SOC_P1
  BB50  VSS_BB50  POWER  = GND
  BB51  VDD_18_S5_BB51  POWER  = PVDD18_S5_P1
  BB52  VSS_BB52  POWER  = GND
  BB53  VDD_18_S5_BB53  POWER  = PVDD18_S5_P1
  BB54  VSS_BB54  POWER  = GND
  BB55  MCA_CA6  OUT  = M_C_CPU1_SA_CA<6>
  BB56  MCA_CA5  OUT  = M_C_CPU1_SA_CA<5>
  BB57  VSS_BB57  POWER  = GND
  BB58  MDA_CA6  OUT  = M_D_CPU1_SA_CA<6>
  BB59  VSS_BB59  POWER  = GND
  BB60  MDA_CA5  OUT  = M_D_CPU1_SA_CA<5>
  BB61  VSS_BB61  POWER  = GND
  BB62  MBA_CA6  OUT  = M_B_CPU1_SA_CA<6>
  BB63  MBA_CA5  OUT  = M_B_CPU1_SA_CA<5>
  BB64  VSS_BB64  POWER  = GND
  BB65  MFA_CA6  OUT  = M_F_CPU1_SA_CA<6>
  BB66  VSS_BB66  POWER  = GND
  BB67  MFA_CA5  OUT  = M_F_CPU1_SA_CA<5>
  BB68  VSS_BB68  POWER  = GND
  BB69  MEA_CA6  OUT  = M_E_CPU1_SA_CA<6>
  BB70  MEA_CA5  OUT  = M_E_CPU1_SA_CA<5>
  BB71  VSS_BB71  POWER  = GND
  BB72  MAA_CA6  OUT  = M_A_CPU1_SA_CA<6>
  BB73  VSS_BB73  POWER  = GND
  BB74  MAA_CA5  OUT  = M_A_CPU1_SA_CA<5>
  BC1  VSS_BC1  POWER  = GND
  BC2  MG0_CLK_H  OUT  = M_G_CPU1_CLK_DP<0>
  BC3  MGA_PAR  OUT  = M_G_CPU1_SA_PAR
  BC4  VSS_BC4  POWER  = GND
  BC5  MK0_CLK_H  OUT  = M_K_CPU1_CLK_DP<0>
  BC6  VSS_BC6  POWER  = GND
  BC7  MKA_PAR  OUT  = M_K_CPU1_SA_PAR
  BC8  VSS_BC8  POWER  = GND
  BC9  ML0_CLK_H  OUT  = M_L_CPU1_CLK_DP<0>
  BC10  MLA_PAR  OUT  = M_L_CPU1_SA_PAR
  BC11  VSS_BC11  POWER  = GND
  BC12  MH0_CLK_H  OUT  = M_H_CPU1_CLK_DP<0>
  BC13  VSS_BC13  POWER  = GND
  BC14  MHA_PAR  OUT  = M_H_CPU1_SA_PAR
  BC15  VSS_BC15  POWER  = GND
  BC16  MJ0_CLK_H  OUT  = M_J_CPU1_CLK_DP<0>
  BC17  MJA_PAR  OUT  = M_J_CPU1_SA_PAR
  BC18  VSS_BC18  POWER  = GND
  BC19  MI0_CLK_H  OUT  = M_I_CPU1_CLK_DP<0>
  BC20  VSS_BC20  POWER  = GND
  BC21  MIA_PAR  OUT  = M_I_CPU1_SA_PAR
  BC22  VSS_BC22  POWER  = GND
  BC23  VDDCR_SOC_BC23  POWER  = PVDDCR_SOC_P1
  BC24  VSS_BC24  POWER  = GND
  BC25  VDDCR_SOC_BC25  POWER  = PVDDCR_SOC_P1
  BC26  VSS_BC26  POWER  = GND
  BC27  VDDCR_SOC_BC27  POWER  = PVDDCR_SOC_P1
  BC28  VSS_BC28  POWER  = GND
  BC48  VDDCR_SOC_BC48  POWER  = PVDDCR_SOC_P1
  BC49  VSS_BC49  POWER  = GND
  BC50  VSS_BC50  POWER  = GND
  BC51  VSS_BC51  POWER  = GND
  BC52  VDD_18_S5_BC52  POWER  = PVDD18_S5_P1
  BC53  VSS_BC53  POWER  = GND
  BC54  VDD_18_S5_BC54  POWER  = PVDD18_S5_P1
  BC55  MCA_PAR  OUT  = M_C_CPU1_SA_PAR
  BC56  VSS_BC56  POWER  = GND
  BC57  MC0_CLK_H  OUT  = M_C_CPU1_CLK_DP<0>
